 
 
Open CloudServer OCS 
Blade Specification 
Version 2.0 
 
 
 
 
 
Author: 
Mark Shaw, Director of Hardware Engineering, Microsoft 
 
 



Open Compute Project  Open CloudServer OCS Blade 
http://opencompute.org ii 
Revision History 
Date Description 
10/30/2014 Version 2.0 
 
  



Open Compute Project  Open CloudServer OCS Blade 
http://opencompute.org iii 
 
© 2014 Microsoft Corporation. 
As of October 30, 2014, the following persons or entities have made this Specification available under the Open Web 
Foundation Final Specification Agreement (OWFa 1.0), which is available at http://www.openwebfoundation.org/legal/the-owf-
1-0-agreements/owfa-1-0 
Microsoft Corporation.  
You can review the signed copies of the Open Web Foundation Agreement Version 1.0 for this Specification at 
http://opencompute.org/licensing/, which may also include additional parties to those listed above. 
Your use of this Specification may be subject to other third party rights. THIS SPECIFICATION IS PROVIDED "AS IS." The 
contributors expressly disclaim any warranties (express, implied, or otherwise), including implied warranties of merchantability, 
noninfringement, fitness for a particular purpose, or title, related to the Specification. The entire risk as to implementing or 
otherwise using the Specification is assumed by the Specification implementer and user. IN NO EVENT WILL ANY PARTY BE 
LIABLE TO ANY OTHER PARTY FOR LOST PROFITS OR ANY FORM OF INDIRECT, SPECIAL, INCIDENTAL, OR CONSEQUENTIAL 
DAMAGES OF ANY CHARACTER FROM ANY CAUSES OF ACTION OF ANY KIND WITH RESPECT TO THIS SPECIFICATION OR ITS 
GOVERNING AGREEMENT, WHETHER BASED ON BREACH OF CONTRACT, TORT (INCLUDING NEGLIGENCE), OR OTHERWISE, AND 
WHETHER OR NOT THE OTHER PARTY HAS BEEN ADVISED OF THE POSSIBILITY OF SUCH DAMAGE. 
CONTRIBUTORS AND LICENSORS OF THIS SPECIFICATION MAY HAVE MENTIONED CERTAIN TECHNOLOGIES THAT ARE MERELY 
REFERENCED WITHIN THIS SPECIFICATION AND NOT LICENSED UNDER THE OWF CLA OR OWFa. THE FOLLOWING IS A LIST OF 
MERELY REFERENCED TECHNOLOGY: INTELLIGENT PLATFORM MANAGEMENT INTERFACE (IPMI), I2C TRADEMARK OF PHILLIPS 
SEMICONDUCTOR. IMPLEMENTATION OF THESE TECHNOLOGIES MAY BE SUBJECT TO THEIR OWN LEGAL TERMS.  



 
iv October 30, 2014 
 
 
Contents 
1 Overview of V2.0 Open CloudServer Specifications ....................................................................................... 1 
2 Introduction to the Open CloudServer System .............................................................................................. 1 
3 Blade Block Diagram ...................................................................................................................................... 3 
4 Blade Features ............................................................................................................................................... 4 
5 Labelling and Loading Guidelines .................................................................................................................. 6 
5.1 DIMMS ......................................................................................................................................................... 6 
5.2 PCIe Riser Slots ............................................................................................................................................. 6 
5.3 HDDs and SSDs ............................................................................................................................................. 7 
6 PCB Stackup .................................................................................................................................................. 7 
7 High-Speed Interface Topologies ................................................................................................................... 9 
7.1 PCIe-to-Tray Backplane Mezzanine Topology .............................................................................................. 9 
7.2 Blade-to-NIC Mezzanine Topology ............................................................................................................. 10 
7.3 JBOD Storage Topology .............................................................................................................................. 10 
7.4 PCIe M.2 Topology ..................................................................................................................................... 11 
7.5 Blade PCIe Riser Topology .......................................................................................................................... 11 
8 Datasafe Storage Support ............................................................................................................................ 11 
8.1 RAID ............................................................................................................................................................ 12 
8.2 M.2 ............................................................................................................................................................. 12 
9 Blade Interconnects ..................................................................................................................................... 12 
9.1 Tray Backplane Interface ............................................................................................................................ 13 
9.1.1 AirMax VS2 PCIe Connector ................................................................................................................... 15 
9.1.2 AirMax VS2 10/40GbE Connector .......................................................................................................... 17 
9.1.3 AirMax VS2 SAS Connector .................................................................................................................... 18 
9.1.4 Connector Skew Compensation ............................................................................................................. 19 
9.2 PCIe M.2 Interposer Modules ..................................................................................................................... 19 
9.3 NIC Mezzanine Connector .......................................................................................................................... 23 
9.4 SATA Cable Ports ........................................................................................................................................ 24 
9.5 SATA Power Connector ............................................................................................................................... 25 
9.6 SATA HDD Connector.................................................................................................................................. 25 
9.7 LED Cable Connector .................................................................................................................................. 26 
10 Management Subsystem ............................................................................................................................. 26 
10.1 Baseboard Management Controller ........................................................................................................... 27 



Open Compute Project  Open CloudServer OCS Blade 
http://opencompute.org v 
 
10.2 DRAM ......................................................................................................................................................... 28 
10.3 BMC Boot Flash .......................................................................................................................................... 28 
10.4 BIOS Flash ................................................................................................................................................... 28 
10.5 Serial Links .................................................................................................................................................. 28 
10.6 PECI ............................................................................................................................................................ 28 
10.7 TPM Module ............................................................................................................................................... 29 
10.8 PCH/BMC I2C .............................................................................................................................................. 29 
10.8.1 Voltage Regulators ............................................................................................................................ 30 
10.8.2 Clock Generators and Buffers ............................................................................................................ 30 
10.8.3 FRUID PROM ...................................................................................................................................... 30 
10.8.4 Temperature Sensors ........................................................................................................................ 30 
10.8.5 Hot Swap Controller .......................................................................................................................... 31 
10.8.6 PCIe I2C .............................................................................................................................................. 33 
10.9 Intel® Node Manager Hardware Requirements ......................................................................................... 33 
10.10 Blade LEDs .............................................................................................................................................. 34 
10.10.1 Blade Power Status LED ..................................................................................................................... 35 
10.10.2 Blade Attention LED .......................................................................................................................... 35 
10.11 Debug Features ...................................................................................................................................... 36 
10.12 Tray Mezzanine Power Control .............................................................................................................. 36 
10.13 Connector Quality .................................................................................................................................. 37 
10.14 Overcurrent Protection .......................................................................................................................... 37 
11 NIC Mezzanine ............................................................................................................................................. 37 
12 Blade Electrical Specifications ..................................................................................................................... 38 
12.1 Input Voltage, Power, and Current ............................................................................................................. 38 
12.2 Current Interrupt Protection and Power, Voltage, and Current Monitoring  .............................................. 39 
12.3 Filtering and Capacitance ........................................................................................................................... 39 
12.4 Grounding and Return ................................................................................................................................ 39 
13 Blade Physical Specifications ....................................................................................................................... 39 
13.1 Blade Mechanical Control Outline .............................................................................................................. 39 
13.2 Volumetric Specifications ........................................................................................................................... 41 
13.3 Weight and Structure ................................................................................................................................. 44 
13.4 Guiding and Latching Features................................................................................................................... 44 
13.4.1 Latching Feature Identification ......................................................................................................... 44 
13.4.2 Guiding and Latching ......................................................................................................................... 45 
13.4.3 Electromagnetic Interference Mitigation .......................................................................................... 47 
 



 
vi October 30, 2014 
 
Table of Figures 
Figure 1: View of OCS with rack ................................ ................................ ................................ ...............  2 
Figure 2: Second view of OCS ................................ ................................ ................................ ...................  2 
Figure 3: V2.0 OCS blade ................................ ................................ ................................ .........................  3 
Figure 4: Baseline configuration of blade ................................ ................................ ................................ . 4 
Figure 5: Major component labelling ................................ ................................ ................................ ....... 6 
Figure 6: PCB Stackup ................................ ................................ ................................ ..............................  8 
Figure 7: CPU-to-tray backplane mezzanine PCIe link topology ................................ ................................  9 
Figure 8: NIC 10GbE/40GbE topology ................................ ................................ ................................ .... 10 
Figure 9: JBOD storage topology ................................ ................................ ................................ ............ 10 
Figure 10: PCIe M.2 topology ................................ ................................ ................................ .................  11 
Figure 11: Blade PCIe riser topology ................................ ................................ ................................ ...... 11 
Figure 12: AirMax power receptacle pinout arrangement ................................ ................................ ...... 13 
Figure 13: Example of a coplanar blade signal connector ................................ ................................ ....... 14 
Figure 14: AirMax VS2 pinout arrangement ................................ ................................ ...........................  15 
Figure 15: Blade management block diagram ................................ ................................ ........................  27 
Figure 16: PCH / BMC I2C block diagram ................................ ................................ ................................  29 
Figure 17: Temperature sensor locations ................................ ................................ ...............................  30 
Figure 18: HSC functional block diagram ................................ ................................ ................................  32 
Figure 19: Front blade LED locations ................................ ................................ ................................ ...... 34 
Figure 20: Rear attention LED location ................................ ................................ ................................ ... 35 
Figure 21:  NIC block diagram ................................ ................................ ................................ ................  38 
Figure 22: Mechanical control outline ................................ ................................ ................................ .... 40 
Figure 23: Dimensions of the volume that holds the blade ................................ ................................ ..... 41 
Figure 24: Two blades on a single tray ................................ ................................ ................................ ... 42 
Figure 25: Blade-mounting envelope, rear view ................................ ................................ .....................  43 
Figure 26: Front surface dimple ................................ ................................ ................................ .............  44 
Figure 27: Guide and latch details, top view................................ ................................ ...........................  46 
Figure 28. Example of a front-blade guide and latch ................................ ................................ ..............  47 
Figure 29: Example of a rear-blade guide pin ................................ ................................ .........................  47 
Figure 30: Tray with EMI enclosure, blade volume shown ................................ ................................ ...... 48 
Figure 31: Blade EMI seal ................................ ................................ ................................ .......................  48 
  



Open Compute Project  Open CloudServer OCS Blade 
http://opencompute.org vii 
 
Table of Tables 
Table 1: List of specifications ................................ ................................ ................................ ...................  1 
Table 2: Blade features ................................ ................................ ................................ ............................  5 
Table 3: Disk drive SATA port assignments ................................ ................................ ...............................  7 
Table 4: PCIe port mapping ................................ ................................ ................................ ......................  8 
Table 5: Blade-to-tray backplane connector list ................................ ................................ .....................  12 
Table 6: Power connector pinout ................................ ................................ ................................ ........... 13 
Table 7: AirMax VS2 PCIe connector pinout ................................ ................................ ...........................  15 
Table 8: AirMax VS2 PCIe signal definitions ................................ ................................ ............................  15 
Table 9: PCIe bifurcation mapping ................................ ................................ ................................ ......... 16 
Table 10: AirMax VS2 10/40GbE connector pinout ................................ ................................ ................  17 
Table 11: AirMax VS2 10/40GbE signal definitions ................................ ................................ .................  17 
Table 12: AirMax VS2 SAS connector pinout ................................ ................................ ..........................  18 
Table 13: AirMax VS2 SAS signal definitions ................................ ................................ ...........................  19 
Table 14: PCIe M.2 interposer connector pinout ................................ ................................ ....................  20 
Table 15: PCIe M.2 carrier signal definitions ................................ ................................ ..........................  22 
Table 16: NIC mezzanine connector part numbers ................................ ................................ .................  23 
Table 17: NIC mezzanine connector pinout ................................ ................................ ............................  23 
Table 18: NIC mezzanine signal descriptions ................................ ................................ ..........................  23 
Table 19: SATA power connector signal names and current capacities ................................ ...................  25 
Table 20: SATA HDD connector pinout ................................ ................................ ................................ ... 26 
Table 22: Signal interpretation ................................ ................................ ................................ ..............  33 
Table 23: Blade power status LED description ................................ ................................ ........................  35 
Table 24: Blade attention LED description ................................ ................................ .............................  35 
Table 25: Input voltage range ................................ ................................ ................................ ................  38 
Table 26: Input power and current allocation ................................ ................................ ........................  38 




Open Compute Project  Open CloudServer OCS Blade 
http://opencompute.org 1 
1 Overview of V2.0 Open CloudServer Specifications 
Table 1 lists the Open CloudServer (OCS) system specifications. 
Table 1: List of specifications 
Specification title Description 
Open CloudServer OCS Chassis 
Specification Version 2.0 
Describes the hardware used in the Version 2.0 (V2.0) OCS 
system, including the chassis, tray, and systems management. 
Open CloudServer OCS Blade 
Specification Version 2.0 
Describes the blade used in the V2.0 OCS system, including 
interconnect and blade hardware and blade management. 
Open CloudServer OCS Tray 
Mezzanine Specification Version 2.0  
Describes the tray mezzanine card used in the V2.0 OCS system, 
including interconnect, hardware, and management. 
Open CloudServer OCS NIC 
Mezzanine Specification Version 2.0  
Describes the Network Interface Controller (NIC) mezzanine card 
used in the V2.0 OCS system. 
Open CloudServer OCS Chassis 
Management Specification Version 
2.0 
Describes the chassis manager command-line interface (CLI). 
This document is intended for designers and engineers who will be building blades for an OCS 
system. 
2 Introduction to the Open CloudServer System 
The V2.0 OCS system is a fully integrated rack of servers and IT equipment that is highly optimized 
and streamlined for large, web-scale deployments.  
OCS is an off-the-shelf (OTS) commodity rack that is loaded with up to four modular chassis, each 
with trays, power supplies, power distribution, rack management, system fans, and two side-walls, 
as shown in Figure 1 and Figure 2. 



 
2 October 30, 2014 
 
 
Figure 1: View of OCS with rack  
 
Figure 2: Second view of OCS 
OCS blades are highly configurable, and are usually compute blades or storage “just a bunch of 
disks” (JBOD) blades.  
Figure 3 shows an example of a V2.0 OCS blade. 


Open Compute Project  Open CloudServer OCS Blade 
http://opencompute.org 3 
 
 
Figure 3: V2.0 OCS blade 
Each chassis supports 12 rack unit (EIA 310-E standard U or 1U, each 17.7" wide and 1.75" tall) trays 
that house up to 24 individual OCS blades (two blades per tray). Blades can be designed to use the 
full width of the tray. It is also possible to use multiple rack units to house a single tall blade, with 
certain restrictions. 
Power, management, and networking are delivered through the tray backplane (TB) and the power 
distribution backplane (PDB). The tray backplane is located at the back of each tray. The power 
distribution backplane attaches vertically to the individual trays on one side and to the power 
supply unit (PSU) on the other side. This arrangement reduces the current carrying requirements of 
the distribution board, eliminates cabling, and reduces costs.  
Power and management signals are received from the PDB and distributed to the blades by 
Ethernet networking cables that pass through a blind-mate connector and are routed to 
attachments at the rear of the chassis. Note that running the cables through the rear of the blade 
eliminates the need to connect directly to the servers. Once provisioned, the network cabling 
should only be touched when a cable or switch fails or the typology is changed. The type and 
number of networking switches depends on the specific deployment. 
Following are the significant changes from the previous generation (V1) of the blade: 
 Support for the Intel® Xeon® Processor E5-2600 v3 product family 
 Support for Intel® C610 series chipset 
 Increased number of Dual Inline Memory Module (DIMM) slots to 16 
 Support for 8 M.2 Solid-State Drive (SSD) modules 
 Support for a tray mezzanine on the tray backplane 
3 Blade Block Diagram 
Figure 4 shows the baseline configuration for the blade. Note that this diagram is provided for 
illustration and is not to scale.  Note also that all requirements are specified in the text of this 
document. 


 
4 October 30, 2014 
 
 
Figure 4: Baseline configuration of blade 
Key features of the blade include: 
 Support for up to four HDDs: two via motherboard connector, two via Serial AT Attachment 
(SATA) cables to the Platform Control Hub (PCH) 
 Support for up to four SATA Small Form Factor (SFF) SSDs via SATA cable to the PCH 
 Support for up to four Samtec Peripheral Component Interconnect Express (PCIe) x8 slots, with 
each slot capable of supporting two M.2 modules through an interposer board  
 Support for a standard PCIe x8 riser card via a Samtec PCIe x8 edge connector 
 Support for a Network Interface Controller (NIC) mezzanine card 
 Support for a tray backplane mezzanine card 
4 Blade Features 
Table 2 lists features supported by the new blade design. 


Open Compute Project  Open CloudServer OCS Blade 
http://opencompute.org 5 
 
Table 2: Blade features 
Processor 
Platform Intel® Xeon® Processor E5-2600 v3 product family platform 
CPU Intel® Xeon® Processor E5-2600 v3 product family 
Sockets Dual and single socket operation 
TDP Wattage Up to 120W 
Memory 
DIMM Slots 16 total DIMM slots 
8 DIMMs per CPU 
2 DIMMs per channel 
DIMM Type Double data rate fourth generation (DDR4)  Registered DIMM (RDIMM) with 
Error-Correcting Code (ECC) 
DIMM Speed DDR4-1600, DDR4-1866, DDR4-2133  
DIMM Size 16GB, 32GB 
Capacities Supported 128GB, 192GB, 256GB, 512GB  
On-board devices 
PCH Intel® C610 series chipset 
SATA 10 ports @ 6.0 Gb/s 
Server management 
Chipset Baseboard Management Controller (BMC)-lite BMC Aspeed AST1050, serial 
through the Chassis Manager 
Interface Representational State Transfer (REST) API 
Windows Management Interface (WMI) 
Open Management Interface (OMI) 
Command-Line Interface (CLI) 
System firmware 
Version, Vendor Unified Extensible Firmware Interface (UEFI) 2.3.1 
Security Trusted Platform Module (TPM 2.0) 
Secure Boot 
PCI-Express expansion 
4 Samtec PCIe x8 slot Slots 1-3 supports M.2 interposer modules 
Slot 4 supports 1 PCI-Express (PCIe) x8 riser or M.2 interposer module 
Tray Mezzanine Card Supports PCIe x16 mezzanine with bifurcation down to PCIe 4x4 



 
6 October 30, 2014 
 
NIC Mezzanine Card Supports PCIe x8 mezzanine 
Networking 
NIC mezzanine card Single 10GbE 
Single 40GbE  
Tray mezzanine card Expansion slot funded by PCIe Gen3 x16 
5 Labelling and Loading Guidelines 
Figure 5 shows the approximate locations of major components on the blade motherboard, along 
with labelling information for referencing the CPU, DIMMs, PCIe riser slots, Hard-Disk Drives 
(HDDs), and SSDs. The sections that follow provide more detail about labelling and loading 
guidelines.   
DIMM C1
DIMM C2
DIMM D1
DIMM D2
CPU0
DIMM B2
DIMM B1
DIMM A2
DIMM A1
DIMM E1
DIMM E2
DIMM F1
DIMM F2
CPU1
DIMM H2
DIMM H1
DIMM G2
DIMM G1
PCIe Riser Slot #1
PCIe Riser Slot #2
PCH
AST1050
PCIe Riser Slot #3
PCIe Riser Slot #4
AirMax2
PCIe
NIC Mezz
AirMax2
GbE
AirMax2
SAS
Alignment
Alignment
12V
s
S
A
T
A
0
s
S
A
T
A
1
HDD 1
HDD 0
HDD 3
HDD 2
  SSD 1 – Top
  SSD 0 – Bottom
sSATA2
 sSATA3
SATA0
SATA1
SATA
2-5
  SSD 3 – Top
  SSD 2 – Bottom
 
Figure 5: Major component labelling 
5.1 DIMMS 
Figure 5 shows how the DIMMs will be labelled. The DIMMs will be color coded to ease loading. 
Two colors will be used: one color for DIMMs A1,B1,C1,D1,E1,F1,G1,H1, and a second color for 
DIMMs A2,B2,C2,D2,E2,F2,G2,H2. Color coding can use either the DIMM connector body or the 
latch. Note that color selection is at the discretion of the manufacturer. 
5.2 PCIe Riser Slots 
The blade contains four PCIe riser slots, as shown in Figure 5. The slots use Samtec connectors to 
provide PCIe connectivity and to meet the height restrictions of the PCIe modules. All slots can 
support M.2 modules. Slot #4 can support either an M.2 module or a standard PCIe card (via PCIe 
riser). The blade can support both low profile and full height PCIe cards. 



Open Compute Project  Open CloudServer OCS Blade 
http://opencompute.org 7 
 
5.3 HDDs and SSDs 
Table 3 shows how the HDD and SSD will be labelled. A label detailing the HDD numbers will be 
available on the frame for reference by service personnel. Table 3 shows the SATA port 
assignments, making it possible to readily locate and service failed drives. Loading of the drives will 
typically be governed by the configuration, but if a configuration supports partial loading, the drives 
should be loaded in numerical order.  
Note that Table 3 details the assignment for two-SSD and four-SSD configurations: for a two-SSD 
configuration, it is anticipated that the optimal solution cables the SSDs from the two single port 
connectors, while for a four-SSD solution, it is anticipated that the optimal solution cables the four 
SSDs from the single four-port connector. 
Table 3: Disk drive SATA port assignments 
Signal name I/O 
SAS_B1_TX[8:1] I 
SAS_B1_RX[8:1] O 
BLADE_B1_EN1 O 
SERIAL_B1_TX1 O 
SERIAL_B1_RX1 I 
JBOD_MATED_N O 
6 PCB Stackup 
Figure 6 shows the recommended 10-layer dual stripline PCB stackup.  The stackup uses standard 
FR4 PCB material.   The PCB thickness requirement will be ~93mils. 
 



 
8 October 30, 2014 
 
 
Figure 6: PCB Stackup 
 
Table 4 lists the recommended PCIe mapping for the design. This mapping is used to determine 
feasibility of stackup support for the PCIe routing. Note that this is informational only; actual 
implementation may vary. 
Table 4: PCIe port mapping 
CPU PCIe bus Destination Layer 
0 PE1A PCIe riser slot #1 1 and 10 
0 PE1B PCIe riser slot #1 1 and 10 
0 PE2A NIC 3 and 8 
0 PE2B NIC 3 and 8 
0 PE2C Not used  
0 PE2D Not used  
0 PE3A Tray backplane mezzanine 1 and 10 
0 PE3B Tray backplane mezzanine 1 and 10 
0 PE3C Tray backplane mezzanine 3 and 8 
0 PE3D Tray backplane mezzanine 3 and 8 
Layer Name Thickness Copper
Weight (oz)
Soldermask 0.5
Signal 1 SIGNAL 1.9 1.5
Prepreg 2.7
Plane 2 GND VDD GND 1.3 1.0
Core 4.0
Signal 3 SIGNAL GND SIGNAL 1.3 1.0
Prepreg 25.0
Signal 4 GND SIGNAL GND 1.3 1.0
Core 4.0
Plane 5 Power GND Power 2.6 2.0
Prepreg 4.0
Plane 6 Power GND Power 2.6 2.0
Core 4.0
Signal 7 GND SIGNAL GND 1.3 1.0
Prepreg 25.0
Signal 8 SIGNAL GND SIGNAL 1.3 1.0
Core 4.0
Plane 9 GND VDD GND 1.3 1.0
Prepreg 2.7
Signal 10 SIGNAL 1.9 1.5
Soldermask 0.5
Total 93.2 +/-9
Layer Type



Open Compute Project  Open CloudServer OCS Blade 
http://opencompute.org 9 
 
CPU PCIe bus Destination Layer 
1 PE1A PCIe riser slot #4 3 and 8 
1 PE1B PCIe riser slot #4 3 and 8 
1 PE2A PCIe riser slot #2 1 and 10 
1 PE2B PCIe riser slot #2 1 and 10 
1 PE2C PCIe riser slot #3 1 and 10 
1 PE2D PCIe riser slot #3 1 and 10 
1 PE3A Not used ---- 
1 PE3B Not used ---- 
1 PE3C Not used ---- 
1 PE3D Not used ---- 
7 High-Speed Interface Topologies 
The sections that follow detail the electrical topologies for the high-speed interfaces connecting the 
external boards/assemblies to the blade.  
7.1 PCIe-to-Tray Backplane Mezzanine Topology 
The blade contains a PCIe x16 Gen3 interface to a mezzanine card on the tray backplane. This link 
connects the CPU to a PCIe port on the mezzanine card. The block diagram in Figure 7 shows the 
connector interfaces and net length estimates for the tray backplane (TBP) and tray mezzanine card 
(TMC). The connector interface between the TBP and the TMC is defined in the V2.0 Open 
CloudServer OCS Chassis Specification. It is estimated that the blade motherboard can support <12” 
of trace between the CPU and the AirMax VS2 connector on the blade. (Note that this is an 
estimate derived for architectural planning and is not intended to replace signal integrity analysis.)  
       Tray Backplane
Tray Mezzanine Card
Blade Motherboard
Airmax
VS2
Airmax
VS2CPU SEAF SEAM PCIe
Port< 2" < 2"< 12"
 
Figure 7: CPU-to-tray backplane mezzanine PCIe link topology 



 
10 October 30, 2014 
 
7.2 Blade-to-NIC Mezzanine Topology 
The blade contains a NIC mezzanine card to provide small form-factor pluggable (SFP+) and Quad 
SFP (QSFP+) cable connectivity to the network switch, as shown in Figure 8.  It is expected that this 
topology will require a retimer on the blade motherboard close to the AirMax VS2 connector to 
support the SFP+.   
Network
SwitchCable
< 3m
Blade Motherboard
  
 NIC Mezz
Tray Backplane
Airmax
VS2
Port1
SFP+ #1L0
40GbE Port
10GbE Port
         40G
     Controller
<1.8"
Network
SwitchCable
< 3m
L3
L2
L1
L0
Airmax
VS2
QSFP+
L2
L3
L1
L0
SEAM SEAF
Port 2
Port 1
L0
L1
L2
L3
L0
L1
L2
L3
L0
L1
L2
L3
L0
L1
L2
L3
Port 2
Port 1
          10G
     Controller
    (Mellanox) L0 Retimer
DS110DF111 <1"
<3.5"
 
Figure 8: NIC 10GbE/40GbE topology 
7.3 JBOD Storage Topology 
The blade contains several topologies for delivering a high speed interface to SATA HDDs.  The 
topologies are intended to support SATA at up to 6Gb/s or SAS at up to 12Gb/s. The block diagram 
in Figure 9 shows the connector and cable interfaces for the JBOD storage topology.  
Tray BackplaneBlade Motherboard
Airmax
VS2
Airmax
VS2
PCIe Mezz Card
SAS
Controller SAS
< 1.8"
Cable
< 240mm
Tray BackplaneJBOD
Airmax
VS2
Airmax
VS2
SAS
Expander SAS
< 1.8"
<2"SAS
CABLE
< 2"
 
Figure 9: JBOD storage topology 
Note that SAS re-timers will not be required on the blade motherboard and will be installed on the 
tray backplane if required. 



Open Compute Project  Open CloudServer OCS Blade 
http://opencompute.org 11 
 
7.4 PCIe M.2 Topology 
The blade contains a PCIe Gen3 interface to an M.2 SSD module. The block diagram in Figure 10 
shows the connector interface for this topology. It is estimated that the blade can support <13.5” of 
trace between the CPU and the HSEC8 high-speed edge card connector on the blade. (Note that 
this is an estimate derived for architectural planning and is not intended to replace signal integrity 
analysis.) 
Blade Motherboard M.2 Module
Edgefinger
ConnCPU 0/1 PCIe
Interface< 2"<13.5"
M.2 Interposer Board
Samtec
HSEC8
Conn
Edgefinger
Conn <3"
PCIe
Conn
 
Figure 10: PCIe M.2 topology 
7.5 Blade PCIe Riser Topology 
The blade contains a PCIe Gen3 interface to standard PCIe card through a riser bridge board. The 
block diagram in Figure 11 shows the connector interface for this topology.  It is estimated that the 
blade can support <12” of trace between the CPU and the standard PCIe connector on the blade.  
(Note that this is an estimate derived for architectural planning and is not intended to replace 
signal integrity analysis.) 
PCIe Bridge BoardBlade Motherboard
PCIe
Conn
Edgefinger
ConnCPU 1
< 5"<12"
PCIe
Conn
PCIe Card
Edgefinger
Conn
PCIe
Interface< 2"
 
Figure 11: Blade PCIe riser topology 
8 Datasafe Storage Support 
The design will support datasafe storage solutions. A datasafe storage device provide nonvolatile 
storage backup for volatile memory, with backup power supplied by a device local energy source 
such as a lithium battery (Redundant Array of Independent Disks [RAID]) or Pfail circuit (M.2):  
 RAID controller 
Uses device local battery solution. Save initiated by PERST#. 
 M.2 
Uses device local PFAIL circuit. Save initiated by PERST#. 



 
12 October 30, 2014 
 
8.1 RAID 
The design will support a RAID controller with battery backup in PCIe SLOT #4. The battery (if 
present) will reside within the volume space designated for the RAID PCIe solution. 
8.2 M.2 
The design will support M.2 storage in PCIe SLOTS 1-4. If the M.2 contains a local PFAIL solution, the 
solution will reside within the volume space designated for the M.2 module. 
9 Blade Interconnects 
The tray (or other supporting infrastructure) provides the electrical interface to the blade using the 
connectors listed in Table 5 (or their functional equivalents). Note that the choice of these 
connectors is based on a coplanar PCB for power and network distribution.  
Table 5: Blade-to-tray backplane connector list 
Qty Connector description  
Blade connector 
Manufacturer Part Number 
(MPN) 
TBP mating connector MPN 
1 AirMax VS power header, 1x2 (FCI) 10028918-001LF 
(or equivalent) 
(FCI) 10052620-4555P00LF 
(or equivalent) 
2 
AirMax VS2 R/A header —3 
pair x 6 column, 54 contact, 
2mm spacing, 17mm pitch, 
(FCI) 10123543-101LF 
(or equivalent) 
(FCI) 10122643-101LF 
(or equivalent) 
1 
AirMax VS2 R/A header —5 
pair x 10 column, 150 contact, 
2mm spacing, 17mm pitch 
(FCI) 10123529-101LF 
(or equivalent) 
(FCI) 10122665-101LF 
(or equivalent) 
2 Guide pin receptacle—
10.8mm right angle, 0° key 
(FCI) 10037912-101LF 
(or equivalent) 
(FCI) 10044366-101LF 
(or equivalent) 
The chassis will provide electrical power and signaling to the tray. The tray will provide power to 
the blade. The blade interface to the tray backplane will provide power and high speed signaling for 
the tray mezzanine card on the tray backplane. 
The interface to the tray backplane from a motherboard shall consist of four connectors: 
1. An AirMax power connector for sourcing 12V power from PDB to blade motherboard. 
2. An AirMax VS2 5x10 primarily to interface PCIe x16 Gen 3 to the tray backplane. 
3. An AirMax VS2 3x6 to interface 10GbE and management signals to the tray backplane. 



Open Compute Project  Open CloudServer OCS Blade 
http://opencompute.org 13 
 
4. An AirMax VS2 3x6 primarily to interface SAS channels to the tray backplane. 
The total amount of force required to mate the blade to the tray backplane will not exceed 18.6 
pounds throughout the expected service life of the connector set. With the leverage provided by 
the latch at the face of the blade, the force required will not exceed 3.15 pounds. The retention 
force of the connectors is a minimum of 5.66 pounds, which equates to 0.94 pounds minimum 
force at the latch. 
9.1 Tray Backplane Interface 
The power connector used is in the FCI AirMax VS connector family.  Figure 12 shows the power 
connector layout. 
 
Figure 12: AirMax power receptacle pinout arrangement 
Table 6 shows the power receptacle pinout 
Table 6: Power connector pinout 
Pin Signal name Capacity (in A) 
Position 1 GND 40A 
Position 2 12V supply 40A 
The maximum power that can be delivered to a blade through this connector is 480W, assuming 
the connector supports 40A with 30⁰C rise. Above this current, the Hot Swap Controller (HSC) 
should disable power to protect the hardware. 
The signal connectors used are from the FCI AirMax VS2. Figure 13 shows an example of an AirMax 
coplanar connector pair. 


 
14 October 30, 2014 
 
 
Figure 13: Example of a coplanar blade signal connector 
There are three AirMax connectors interfacing the blade to the tray backplane: 
 AirMax VS2 5x10 connector   
This connector is primarily responsible for interfacing PCIe x16 Gen 3 from the blade CPU to the 
tray mezzanine card on the tray backplane.   
 AirMax VS2 3x6 connector  
This connector is responsible for interfacing 10GbE, 40GbE, and management signals from the 
Blade to the tray backplane. This connector is mate compatible with the V1.0 Open CloudServer 
blade. 
 AirMax VS2 3x6 connector  
This connector is primarily responsible for interfacing eight 12G SAS channels to the tray 
backplane for storage expansion. This connector is mate compatible with the V1.0 Open 
CloudServer blade.  
The previous-generation blade used the AirMax VS 3x6 connector.  Note that the VS and VS2 family 
connectors are plug-in compatible. 
The AirMax connector is organized as a grid, with rows A through L and columns 1 through 10. Note 
that the columns flip from header to receptacle so that the mated pairs match. Figure 14 shows the 
signal connector layout, with the blade header on the left and the tray backplane receptacle on the 
right.  


Open Compute Project  Open CloudServer OCS Blade 
http://opencompute.org 15 
 
 
Figure 14: AirMax VS2 pinout arrangement 
9.1.1 AirMax VS2 PCIe Connector 
Table 7 shows the signal breakout for the AirMax PCIe header. 
Table 7: AirMax VS2 PCIe connector pinout 
 
Table 8 describes the signals used in this interface. 
Table 8: AirMax VS2 PCIe signal definitions 
Bus type I/O Logic Definition for three pair, eight column 
PCIE_B2T_TX_DP/N[15:0] O 
Current 
Mode 
Logic 
(CML) 
PCIe Gen 3 data from blade to tray mezzanine 
PCIE_T2B_RX_DP/N[15:0] I CML PCIe Gen3 data from tray mezzanine to blade 
CLK_100M_P/N[3:0] O CML 100MHz PCIe Gen 3 clocks 
PCIE_RESET_N[3:0]  O 3.3V PCIe reset signals 
WAKE_PCIE_N I 3.3V PCIe wake signal 
PCIE_CFG_ID[1:0] I 3.3V 
PCIe configuration ID bits 
Should be connected to General Purpose Input/Output 
(GPIO) on the PCH 
Should be pulled up with minimum 10K ohm resistor 


 
16 October 30, 2014 
 
Bus type I/O Logic Definition for three pair, eight column 
Has 1K pulldown on tray mezzanine 
00 = 1 x16 bifurcation 
01 = 2 x8 bifurcation 
10 = 4 x4 bifurcation 
11 = N/A 
PCIE_B2T_TX_DP/N[15:0] O CML PCIe Gen 3 data from blade to tray mezzanine 
MEZZ_SDA/SCL I/O 3.3V I2C from blade BMC to tray mezzanine 
MEZZ_PRESENT_N I 3.3V 
Indicates tray mezzanine card is installed 
This signal should be pulled up on the blade and 
grounded on the tray mezzanine card 
MEZZ_EN O 3.3V Enable for tray mezzanine card on-board power 
P12V_MEZZ O 12V Tray mezzanine card 12V power from blade 12V HSC (3A) 
BLADE_MATED_N I 3.3V 
Indicates blade is mated to tray backplane through 
AirMax 5x10 
Grounded on tray backplane 
Should be pulled up on blade and used to qualify 12V in-
rush turn on 
USBP/N I/O CML USB 2.0 from blade 
P5V_USB O 5V 5V USB power (500mA) 
RSVD -- -- Reserved—do not connect 
GND -- -- Ground 
P12V_MEZZ and P5V_USB pins are assumed to support a derated 500mA per pin; therefore, 
P12V_MEZZ supports a derated maximum of 3A, and P5V_USB supports 500mA. 
Table 9 shows how the reset and clock signals are mapped to support each of the bifurcation cases 
for PCIe to the tray mezzanine. 
Table 9: PCIe bifurcation mapping 
 1x16 2x8 4x4 
 SIGNAL NAME 15:0 15:8 7:0 15:12 11:8 7:4 3:0 
PCIE_RESET_N[0] X X  X    
PCIE_RESET_N[1]   X  X   
PCIE_RESET_N[2]      X  



Open Compute Project  Open CloudServer OCS Blade 
http://opencompute.org 17 
 
 1x16 2x8 4x4 
 SIGNAL NAME 15:0 15:8 7:0 15:12 11:8 7:4 3:0 
PCIE_RESET_N[3]       X 
CLK_100M_P/N[0] X X  X    
CLK_100M_P/N[1]   X  X   
CLK_100M_P/N[2]      X  
CLK_100M_P/N[3]       X 
9.1.2 AirMax VS2 10/40GbE Connector 
Table 10 shows the pinout for the AirMax 10Gb/40Gb Ethernet header.  
Table 10: AirMax VS2 10/40GbE connector pinout 
 
Table 11 describes the signals used in this interface. 
Table 11: AirMax VS2 10/40GbE signal definitions 
Bus type I/O Logic Definition for three pair, eight column 
ETH10G_TXP/N O CML 10Gb Ethernet from blade NIC to SFP+ connector 
ETH10G_RXP/N I CML 10Gb Ethernet from SFP+ connector to blade NIC 
ETH40G_TX[3:0]P/N O CML 40Gb Ethernet from blade LOM to QSFP+ connector 
ETH40G_RX[3:0]P/N I CML 40Gb Ethernet from QSFP+ connector to blade NIC mezz 
ENET_40G_SDA/SCL I/O 3.3V I2C from Ethernet controller on blade to QSFP+ 
connector/cable 
ENET40G_PRES_N I 3.3V Indicates presence of 40GbE cable from QSFP+ connector 
ENET10G_SDA/SCL I/O 3.3V I2C from Ethernet controller on blade to SFP+ 
connector/cable 
GND ETH40G_RX1P GND ETH40G_RX2P GND ETH40G_TX3P A
ETH40G_TX1P ETH40G_RX1N ETH40G_TX2P ETH40G_RX2N ETH40G_RX3P ETH40G_TX3N B
ETH40G_TX1N GND ETH40G_TX2N GND ETH40G_RX3N GND C
GND P3V3_QSFP GND ETH10G_SDA GND ETH10G_RXP D
ETH40G_RX0P P3V3_QSFP ETH40G_SDA ETH10G_SCL RSVD ETH10G_RXN E
ETH40G_RX0N GND ETH40G_SCL SKU_ID0 SKU_ID2 GND F
GND PSU_ALERT_N SERIAL_RX2 SERIAL_RX1 GND ETH10G_TXP G
ETH40G_TX0P ETH40G_PRES_N SERIAL_TX2 SERIAL_TX1 BLADE_EN1 ETH10G_TXN H
ETH40G_TX0N BLADE_MATED_N SKU_ID1 P3V3_QSFP ETH10G_PRES_N GND I
6 5 4 3 2 1



 
18 October 30, 2014 
 
Bus type I/O Logic Definition for three pair, eight column 
ENET10G_PRES_N I 3.3V Indicates presence of 10GbE cable through DAC 
PRESENT_N signal from SFP+ connector 
SKU_ID<2:0> I 3.3V 3.3V Pu/Pd on TBP indicating the SKU of the tray 
backplane 
P3V3_QSFP O 3.3V QSFP+ and SFP+ cable power 
BLADE_MATED_N I 3.3V 
Indicates blade is mated to tray backplane through AirMax 
3x6 
Grounded on tray backplane 
Should be pulled up on blade and used to qualify 12V in-
rush turn on 
SERIAL_TX[2:1] I 3.3V 
Serial communication ports from the Chassis Manager 
(CM) to blade 
Two nodes per blade from CM  
SERIAL_RX[2:1] O 3.3V Serial communication port from blade to CM 
Two nodes per blade from CM 
BLADE_EN1 I 3.3V Blade enable signal from CM 
Used to enable the 12V in-rush controller 
PSU_ALERT_N I 3.3V 
Power supply failure alert 
This signal is active low (open drain) and should be pulled 
up on the motherboard     
RSVD I/O  Reserved—do not connect 
Ground --  Ground pins 
9.1.3 AirMax VS2 SAS Connector 
Table 12 shows the pinout for the AirMax SAS connector. Connector #1 supports SAS lanes 1-8. 
Table 12: AirMax VS2 SAS connector pinout 
 
GND SAS_TX6P GND RSVD GND SAS_TX1P A
SAS_RX8P SAS_TX6N RSVD RSVD SAS_RX3P SAS_TX1N B
SAS_RX8N GND RSVD GND SAS_RX3N GND C
GND SAS_RX6P GND SAS_RX4P GND SAS_RX1P D
SAS_TX8P SAS_RX6N SAS_TX5P SAS_RX4N SAS_TX3P SAS_RX1N E
SAS_TX8N GND SAS_TX5N GND SAS_TX3N GND F
GND SAS_TX7P GND SAS_TX4P GND SAS_TX2P G
SAS_RX7P SAS_TX7N SAS_RX5P SAS_TX4N SAS_RX2P SAS_TX2N H
SAS_RX7N GND SAS_RX5N GND SAS_RX2N GND I
6 5 4 3 2 1



Open Compute Project  Open CloudServer OCS Blade 
http://opencompute.org 19 
 
Table 13 describes the signals used in this interface. 
Table 13: AirMax VS2 SAS signal definitions 
Bus type I/O Logic Definition for three pair, eight column 
SAS_TX[8:1] O CML SAS 8-channels from Blade to SAS cable 
SAS_RX[8:1] I CML SAS 8-channels from SAS cable to blade 
RSVD I/O -- Reserved—do not connect 
Ground -- -- Ground pins 
9.1.4 Connector Skew Compensation 
Right-angle AirMax VS2 connector interfaces between the tray backplane and the blade 
motherboard will require signal delay compensation in the PCB to account for differences in pin 
length of a P/N differential pair in the mated connectors. The pin-pair skew can be obtained from 
the connector manufacturer.  
Following are the skew compensation divisions between the blade motherboard and the tray 
backplane: 
 AirMax VS2 PCIe connector 
All skew compensation is contained on the blade motherboard. 
 AirMax VS2 GbE connector 
All skew compensation is contained on the Blade Motherboard. 
 AirMax VS2 SAS connector  
Half (50%) of skew compensation is contained on the blade motherboard. Skew compensation 
for the VS2 connector pair is divided equally between the blade motherboard and the tray 
backplane. 
9.2 PCIe M.2 Interposer Modules 
The blade will support the M.2 interposer module, a custom edge card that supports two M.2 SSD 
modules (Next Generation Form Factor [NGFF] cards) in the connectorized SSD socket 3 format per 
the PCIe M.2 specification.   
The interposer edge card interfaces to the blade motherboard through a Samtec HSEC8-150-01-S-
DV-A connector (or equivalent). The interposer module supports the 60mm, 80mm, and 110mm 
form factors (Type 2260, 2280, and 22110). To support two M.2 modules, the connector interface is 
designed to support two PCIe Gen3x4 interfaces as well as the SSD specific signals, per the PCIE M.2 
specification.  



 
20 October 30, 2014 
 
The interface is also designed to support a standard PCIe x8 interface through a separate riser card. 
The bifurcation is communicated through the LINK_WIDTH signal (Pin B3), which should be 
connected to the PCH. The PCIe card will not require I2C or Joint Test Action Group (JTAG) 
connections to the motherboard. Table 14 shows the pinout for supporting only the M.2 interposer 
module. 
Table 14: PCIe M.2 interposer connector pinout 
 Side B connector  Side B connector 
Pin Name Description Pin Name Description 
1 12V 12V power 2 PRSNT1# Hot plug presence detect 
3 12V 12V power 4 12V 12V power 
5 LINK_WIDT
H 
0=1 x8, 1= 2x4 
bifurcation 6 12V 12V power 
7 GND Ground 8 GND Ground 
9 REFCLK2+ Module 2 reference 
clock differential pair 
10 CLKREQ1 Ref clock request (OD) 
11 REFCLK2- 12 CLKREQ2 Ref clock request (OD) 
13 GND Ground 14 SUSCLK Suspend  cock (32.768Khz) 
15 3.3V 3.3V power 16 DAS/DSS# Drive active indicator 
17 DEVSLP Device sleep 18 3.3V 3.3V power 
19 3.3V 3.3V power 20 3.3V 3.3V power 
21 WAKE# Ground 22 PERST# PCIe reset 
23 3.3V STBY 3.3V standby power 24 GND Ground 
25 GND Ground 26 REFCLK1+ Module 1 reference clock 
differential pair 27 PETp(0) Transmitter module 1 
lane 0 differential pair 
28 REFCLK1- 
29 PETn(0) 30 GND Ground 
31 GND Ground 32 PERp(0) Receiver module 1 lane 0 
differential pair 33 PRSNT2# Hotplug detect 34 PERn(0) 
35 GND Ground 36 GND Ground 
37 PETp(1) Transmitter module 1  
lane 1 differential pair 
38 RSVD Reserved 
39 PETn(1) 40 GND Ground 
41 GND Ground 42 PERp(1) Receiver module 1 lane 1 
differential pair 43 GND Ground 44 PERn(1) 
45 PETp(2) Transmitter module 1  46 GND Ground 



Open Compute Project  Open CloudServer OCS Blade 
http://opencompute.org 21 
 
 Side B connector  Side B connector 
Pin Name Description Pin Name Description 
47 PETn(2) lane 2 differential pair 48 GND Ground 
49 GND Ground 50 PERp(2) Receiver module 1 lane 2 
differential pair 51 GND Ground 52 PERn(2) 
53 GND Ground 54 GND Ground 
Mechanical key 
55 PETp(3) Transmitter module 1  
lane 3 differential pair 
56 GND Ground 
57 PETn(3) 58 GND Ground 
59 GND Ground 60 PERp(3) Receiver module 1 lane 3 
differential pair 61 RSVD Reserved 62 PERn(3) 
63 PRSNT3# Hot plug detect 64 GND Ground 
65 GND Ground 66 RSVD Reserved 
67 PETp(4) Transmitter module 2  
lane 0 differential pair 
68 RSVD Reserved 
69 PETn(4) 70 GND Ground 
71 GND Ground 72 PERp(4) Receiver module2  lane 0 
differential pair 73 GND Ground 74 PERn(4) 
75 PETp(5) Transmitter module 2  
lane 1 differential pair 
76 GND Ground 
77 PETn(5) 78 GND Ground 
79 GND Ground 80 PERp(5) Receiver module2  lane 1 
differential pair 81 GND Ground 82 PERn(5) 
83 PETp(6) Transmitter module 2  
lane 2 differential pair 
84 GND Ground 
85 PETn(6) 86 GND Ground 
87 GND Ground 88 PERp(6) Receiver module2  lane 2 
differential pair 89 GND Ground 90 PERn(6) 
91 PETp(7) Transmitter module 2  
lane 3 differential pair 
92 GND Ground 
93 PETn(7) 94 GND Ground 
95 GND Ground 96 PERp(7) Receiver module2  lane 3 
differential pair 97 PRSNT4# Hot plug detect 98 PERn(7) 
99 GND Ground 100 GND Ground 



 
22 October 30, 2014 
 
Signals will satisfy the electrical requirements of the PCIe M.2 Specification and the PCIe Card 
Electromechanical Specification. Note that table includes columns to indicate whether a signal is 
required for use by the M.2 interposer module and/or the PCIe riser. Only slot 4 is required to 
support both the M.2 Interposer and PCIe Riser. 
Table 15 provides a brief functional description of each signal.  
Table 15: PCIe M.2 carrier signal definitions 
Bus type I/O Voltage M.2 interposer PCIe riser Definition for three pair, eight 
column 
P12V O 12V  X 12V Input  
P3V3 O 3.3V X X 3.3V Input  
WAKE# I 3.3V X X PCIe Wake for M.2 modules 1 and 2 
PERST# O 3.3V X X PCIe Reset for M.2 modules 1 and 2 
PETP/N(3:0) O  X X PCIe Transmit to M.2 module 1 
PERP/N[3:0] O  X X PCIe Receiver from M.2 module 1 
REFCLK1LP/N O  X X Reference Clock for module 1 
PETP/N[7:4] O  X X PCIe Transmit to M.2 module 2 
PERP/N[7:4] O  X X PCIe Receive from M.2 module 2 
REFCLK2P/N O  X  Reference clock for module 2 
SUSCLK I  X  Suspend Clock for modules 1 and 2 
(32.768Khz) 
CLKREQ1 I  X  Reference Clock Request for 
module 1 
CLKREQ2 I  X  Reference Clock Request for 
module 2 
DEVSLP O  X  Device Sleep to M.2 modules 1 and 
2 (should be pulled low on MB) 
RSVD N/A  X X Reserved (do not connect) 
PRSNT[3:1] I/O  X X 
Present 
Should be connected on MB per 
PCIe specification 
GND I/O  X X Ground 



Open Compute Project  Open CloudServer OCS Blade 
http://opencompute.org 23 
 
9.3 NIC Mezzanine Connector 
The blade will support a single NIC mezzanine card. The mezzanine will interface to the blade 
through a Samtec SEAF-20-06.5-L-08-2-A-K-TR connector or equivalent.  
Table 16 lists the compatible connectors. 
Table 16: NIC mezzanine connector part numbers 
Manufacturer Card connector MPN Motherboard connector MPN 
Samtec SEAM-20-03.5-L-08-2-A-K-TR SEAF-20-06.5-L-08-2-A-K-TR 
Molex 45970-2385 45971-2385 
Table 17 shows the pinout for the NIC mezzanine connector.  
Table 17: NIC mezzanine connector pinout 
 
Table 18 describes the signals used in this interface. 
Table 18: NIC mezzanine signal descriptions 
Bus type I/O Logic Definition 
P3E_CPU1_LAN_RX_DP/N[7:0] I CML PCIe Gen3 from the NIC mezzanine to the CPU 
P3E_CPU1_LAN_TX_DP/N[7:0] O CML PCIe Gen3 from the CPU to the NIC mezzanine 
CLK_100M_NIC_PE_DP/N O CML 100MHz PCIe clock 
PCIE_RESET_N O 3.3V PCIe reset 
MEZZ_PRESENT_N I 3.3V Mezzanine present 
Should be GND on mezzanine  
NWK_1_TX[3:0]P/N I CML Port 1 10GbE transmit from mezzanine to tray 
backplane 
8 CLK_100M_NIC_PE_DP GND SMB_ALERT_N NIC_MEZZ_ID0 PCIE_WAKE_N GND PCIE_RESET_N GND 1
16 CLK_100M_NIC_PE_DN GND NWK2_PRESENT_N SMB_SCL GND P3E_CPU1_LAN_RX_DP<7> GND P3E_CPU1_LAN_TX_DP<0> 9
24 GND MEZZ_PRESENT_N GND SMB_SDA GND P3E_CPU1_LAN_RX_DN<7> GND P3E_CPU1_LAN_TX_DN<0> 17
32 NWK_2_TX0P GND NWK_1_TX1P GND P3E_CPU1_LAN_RX_DP<6> GND P3E_CPU1_LAN_TX_DP<1> GND 25
40 NWK_2_TX0N GND NWK_1_TX1N GND P3E_CPU1_LAN_RX_DN<6> GND P3E_CPU1_LAN_TX_DN<1> GND 33
48 GND NWK_2_TX1P GND NWK_1_TX2P GND P3E_CPU1_LAN_RX_DP<5> GND P3E_CPU1_LAN_TX_DP<2> 41
56 GND NWK_2_TX1N GND NWK_1_TX2N GND P3E_CPU1_LAN_RX_DN<5> GND P3E_CPU1_LAN_TX_DN<2> 49
64 NWK_2_TX2P GND NWK_1_TX3P GND P3E_CPU1_LAN_RX_DP<4> GND P3E_CPU1_LAN_TX_DP<3> GND 57
72 NWK_2_TX2N GND NWK_1_TX3N GND P3E_CPU1_LAN_RX_DN<4> GND P3E_CPU1_LAN_TX_DN<3> GND 65
80 GND NWK_2_TX3P GND NWK_1_RX1N GND P3E_CPU1_LAN_RX_DP<0> GND P3E_CPU1_LAN_TX_DP<4> 73
88 GND NWK_2_TX3N GND NWK_1_RX1P GND P3E_CPU1_LAN_RX_DN<0> GND P3E_CPU1_LAN_TX_DN<4> 81
96 NWK_2_RX0P GND NWK_1_RX2N GND P3E_CPU1_LAN_RX_DP<1> GND P3E_CPU1_LAN_TX_DP<5> GND 89
104 NWK_2_RX0N GND NWK_1_RX2P GND P3E_CPU1_LAN_RX_DN<1> GND P3E_CPU1_LAN_TX_DN<5> GND 97
112 GND NWK_2_RX1N GND NWK_1_RX3N GND P3E_CPU1_LAN_RX_DP<2> GND P3E_CPU1_LAN_TX_DP<6> 105
120 GND NWK_2_RX1P GND NWK_1_RX3P GND P3E_CPU1_LAN_RX_DN<2> GND P3E_CPU1_LAN_TX_DN<6> 113
128 NWK_2_RX2N GND NWK_1_TX0P GND P3E_CPU1_LAN_RX_DP<3> GND P3E_CPU1_LAN_TX_DP<7> GND 121
136 NWK_2_RX2P GND NWK_1_TX0N GND P3E_CPU1_LAN_RX_DN<3> GND P3E_CPU1_LAN_TX_DN<7> NWK2_I2C_SDA 129
144 GND NWK_2_RX3N GND NWK_1_RX0P GND NIC_MEZZ_ID1 GND NWK2_I2C_SCL 137
152 NWK1_I2C_SDA NWK_2_RX3P GND NWK_1_RX0N GND P3V3 P3V3_AUX P12V_AUX 145
160 NWK1_I2C_SCL GND NWK1_PRESENT_N GND P3V3 P3V3 P3V3_AUX P12V_AUX 153



 
24 October 30, 2014 
 
Bus type I/O Logic Definition 
NWK_1_RX[3:0]P/N O CML Port 1 10GbE receive from motherboard to tray 
backplane 
NWK_2_TX[3:0]P/N I CML Port 2 40GbE transmit from mezzanine to tray 
backplane 
NWK_2_RX[3:0]P/N O CML Port 2 40GbE receive from tray backplane to 
mezzanine 
SMB_ALERT_N I 3.3V I2C Alert from NIC mezzanine to BMC 
NWK1_PRESENT_N O 3.3V Port 1 cable present indicator from tray backplane 
NWK1_I2C_SDA I/O 3.3V Port1 I2C data to SFP+ cable 
NWK1_I2C_SCL I 3.3V Port 1 I2C clock to SFP+ cable 
NWK2_PRESENT_N O 3.3V Port 2 cable present Indicator from tray backplane 
NWK2_I2C_SDA I/O 3.3V Port 2 I2C data to QSFP+ cable 
NWK2_I2C_SCL I 3.3V Port 2 I2C clock to QSFP+ cable 
PCIE_WAKE_N I 3.3V PCIe wake  
SMB_SCL O 3.3V I2C to BMC 
SMB_SDA I/O 3.3V I2C to BMC 
NIC_MEZZ_ID[1:0] I 3.3V NIC mezzanine ID 
Should connect to BMC 
P3V3 O 3.3V 3.3V input power 
P3V3_AUX O 3.3V 3.3V auxiliary input power 
P12V_AUX O 12V 12V input power 
Ground -- -- Ground pins 
9.4 SATA Cable Ports 
The board will include support for one x4 Mini-SAS HD connector, supporting the SFF-8643 (or 
equivalent) cable and four x1 SATA connectors for cabling SATA ports from the PCH to the HDDs 
and SSDs. 



Open Compute Project  Open CloudServer OCS Blade 
http://opencompute.org 25 
 
9.5 SATA Power Connector 
The board will include four 4-pin Mini-Fit® Jr 5566 series power connectors, P/N: Molex 5566-04A 
(or equivalent). Two connectors are intended to provide power to the Large Form Factor (LFF) HDDs 
and SSDs. Each connector is intended to provide cabled power to two drives. Each connector pin 
has a maximum 13A current capacity.  
The 12V and 5V power rails are supplied directly from the main 12V and 5V power supply rails. 
These rails need to drive at most six 3.5” LFF HDDs or Small Form Factor (SFF) SSDs. Table 19 lists 
the signal names and current capacities. 
Table 19: SATA power connector signal names and current capacities 
Pin Signal name Capacity (in A) 
Pin 1 and 2 GND 26A (Black) 
Pin 3 12V 13A (Yellow) 
Pin 4 5V 13A (Red) 
9.6 SATA HDD Connector 
The board will include two connectors for connecting up to two SATA HDDs to the motherboard.  
The connectors will be FCI P/N 10029364001LF (or equivalent). Table 20 shows the industry 
standard pinout. The remaining two HDDs should be mounted to fixed connectors on the blade 
pan. 



 
26 October 30, 2014 
 
Table 20: SATA HDD connector pinout 
 
9.7 LED Cable Connector 
The design will provide connector support for an LED cable for driving the two LEDs on the front 
panel. 
10 Management Subsystem 
Management circuitry for the blade uses the Intel® Manageability Engine (ME) combined with the 
Baseboard Management Controller (BMC). This section describes the requirements for 
management of the blade. Primary features include: 
 Intel® Manageability Engine (ME) 
 BMC chip (ASPEED AST1050) 
 BMC serial link (universal asynchronous receiver/transmitter [UART]) for communication with 
Chassis Manager 
Pin Signal Name Signal Description
1 GND Ground
2 A+ Transmit +
3 A- Transmit -
4 GND Ground
5 B- Receive -
6 B+ Receive +
7 GND Ground
Pin Signal Name Signal Description
1 V33 3.3v Power
2 V33 3.3v Power
3 V33 3.3v Power, Pre-charge, 2nd mate
4 Ground 1st Mate
5 Ground 2nd Mate
6 Ground 3rd Mate
7 V5 5v Power, pre-charge, 2nd mate
8 V5 5v Power
9 V5 5v Power
10 Ground 2nd Mate
11 Optional GND -
12 Ground 1st Mate
13 V12 12v Power, Pre-charge, 2nd mate
14 V12 12v Power
15 V12 12v Power
Power
Data



Open Compute Project  Open CloudServer OCS Blade 
http://opencompute.org 27 
 
 Low Pin Count (LPC) connection to the chipset to support in-band management 
 Platform Environmental Control Interface (PECI) for CPU out-of-band environmental control 
 FRUID Electrically Erasable Programmable Read-Only Memory (EEPROM) for storage of 
manufacturing data and event  
 Thermal sensors for inlet and exhaust temperature monitoring 
 Power monitoring through the 12V hot swap controller circuitry 
 Service LEDs 
Figure 15 shows the management block diagram.   
Chassis
Manager
                          Blade Motherboard
PCH
BMC
AST1050
16MB BIOS
FLASH
Tray
Backplane
CPU 0
4GB/s
Port 80
POST LEDs
CPU 1
TPM 
Connector CPLD
9.6GT/s
QPI0
QPI1
9.6GT/s
QPI1
QPI0
DMI2
LPC LPC
SPI UART3
UART1
GPIO
UART1
UART2
SKU_ID[2:0]
PECI
PECI
PECI
UART5 BMC Debug
Connector
USB USB 2.0 
Connector
XDP
Connector
GPIO
JUMPER GPIODisable BMC
JUMPER Force Bios Recovery
SATA x1
Connector
SATA x1
Connector
SATA x1
Connector
sSATA[0]
SATA x4
Mini SAS HD
sSATA[1]
SATA[0]
SATA[5:2]
JTAG
JTAG
4-pin Hdr
4-pin Hdr
DMI2
BMC/CM
Connector
Console Dbg
Connector 4-pin Hdr
4-pin Hdr
16MB BMC
FLASH
SPI
GPIO
12V HSCSVID
SVID
VRD
VccIN
VRD
DDR4 C/D
VRD
DDR4 A/B
VRD
VccIN
VRD
DDR4 C/D
VRD
DDR4 A/B
Front Attention LED
GPIO
Rear Attention LED
Power Status LED
BLADE_EN1
BLADE_EN2
BLADE_MATED_N<1:0>
JUMPER Flash Security OverrideGPIO
JUMPER Clear CMOSGPIO
SATA x1
HDD Conn
SATA x1
HDD Conn
SATA x1
Connector
SATA[1]
sSATA[2]
sSATA[3]
DRAM
128MB
CPLD
HDD #4
HDD #3
HDD #4
HDD #1
HDD #2
HDD #3
USB USB 2.0 
Connector
USB
Tray
Mezz
4-pin Hdr
MEZZ_EN
MEZZ_PRESENT_N
GPIO
GPIO
 
Figure 15: Blade management block diagram 
10.1 Baseboard Management Controller 
The design for the BMC is based on the ASPEED AST1050 processor. Primary features of interest for 
the AST1050 include: 
 Embedded ARM926EJ 
 Embedded 16KB/16KB cache 
 Synchronous Dynamic Random Access Memory (SDRAM) memory up to 512MB 
 NOR/NAND/Serial Peripheral Interface (SPI) flash memory 
 I2C System Management Bus (SMBus) controller 
 5 UART 16550 controllers 
 LPC bus interface 



 
28 October 30, 2014 
 
 Up to 152 GPIO pins 
10.2 DRAM 
The BMC requires 128 MB of Double Data Rate 3 (DDR3) memory. 
10.3 BMC Boot Flash 
The BMC boots from a flash memory device located on the SPI bus. The device size will be 128Mb 
(16MB) minimum. Winbond W25Q128 serial flash memory (or equivalent) is recommended. The 
design will support a socket for this device during pre-production. 
10.4 BIOS Flash 
The blade will support a 128Mb (16MB) flash BIOS located on the PCH SPI bus: Winbond MPN 
W25Q128BVGFIG (or equivalent). It is required to operate at 50 MHz and include Quad I/O Fast 
Read Support. The design will support a socket for this device during pre-production. The design 
shall also include a BIOS recover jumper connected to a PCH GPIO. 
10.5 Serial Links 
The blade is managed from Chassis Manager through a serial port connection to the BMC. There 
are two dedicated 3.3V serial links (UARTs) routed to the blade. The BMC supports a third UART for 
debug use only. The following is a brief description of the BMC UART port assignments and their 
uses: 
 UART3 
Primary communication with CM for control of the blade. 
 UART1 
Secondary communication with CM; primarily used for console debug. 
 UART5 
BMC debug port; connects only to a debug connector on the blade. 
10.6 PECI 
The blade shall use the PECI host controller inside the CPU to support integrated thermal 
monitoring of the two CPU sockets.   



Open Compute Project  Open CloudServer OCS Blade 
http://opencompute.org 29 
 
10.7 TPM Module 
The blade will include a connector to support a tamper-proof Trusted Platform Module (TPM) 2.0 
solution. 
10.8 PCH/BMC I2C 
The design will include a number of I2C devices/functions available to the BMC and PCH. The block 
diagram is shown below in Figure 16.  A brief description of the components follows. Some of the 
block components are specific with respect to requirements of the device and its slave address, 
while others (such as voltage regulators) are more general, requiring that the functionality be 
placed on a specific I2C bus but not requiring a specific solution (vendor part number) be used. 
Care should be taken to electrically isolate components that are powered from separate power 
domains, but are located on the same I2C bus. Note that addresses shown are 8-bit address with 
the Read/Write (R/W) bit as the Least Significant Bit (LSB) set to 0 (0xA8=1010100x). Figure 16 
shows a block diagram. 
Intel® 
ME
PCH BMC
AST1050
VRD
CPU0
VRD
DDR4 VDD
VRD
CPU1
VRD
DDR4 VDD
MEXP_SMB0
TMP75
Blade Inlet
0x92
TMP75
Blade Outlet
0x90
MEXP_SMB1
MEXP_SMB2
SD6
AT24C64
FRUID
0xA8
ICS9FGP204 
CLKGEN
0xD0
CPU XDP
Connector
932SQ420 
CLKBUF
0xD2
ICS9ZX21901 
CLKBUF
0xD8
SD4
PCA9617
I2C Extender
VRD
PCH
SMB
SD2
SD3
SML0
SD7SML1
12V
HSC
0x20 or 0x40
Debug
Debug
Debug
Debug
Debug
Tray
Mezzanine
SD5
DebugNIC
Mezzanine
10GbE
Retimer
 
Figure 16: PCH / BMC I2C block diagram 



 
30 October 30, 2014 
 
10.8.1 Voltage Regulators 
Voltage regulators that support I2C or PMBus should be available to PCH MEXP_SMB0, PCH SMB, 
and BMC I2C Port 3. This includes CPU and memory subsystem regulators, at a minimum. The Intel® 
ME is responsible for enabling power (through a programmable logic device) to any voltage 
regulators that are not on AUX power (i.e., enabled automatically by the presence of 12V). 
10.8.2 Clock Generators and Buffers 
Clock circuitry that supports I2C should be available to PCH MEXP_SMB0, PCH SMBus, and BMC I2C 
Port 3. The block diagram shows three clock devices that are common to this architecture (actual 
implementation may vary). 
10.8.3 FRUID PROM 
The blade will include a 64Kb serial EEPROM MPN AT24C64 (or equivalent) to store manufacturing 
data. The device should be available to PCH MEXP_SMB0, PCH SMB, and BMC I2C Port 3. 
10.8.4 Temperature Sensors 
The blade will include support for a minimum of two temperature sensors, MPN TMP75 (or 
equivalent), for monitoring the inlet and outlet temperatures of the blade. The sensors will be 
available on BMC I2C port 6. Figure 17 shows temperature sensor locations on the blade.   
 
Figure 17: Temperature sensor locations 


Open Compute Project  Open CloudServer OCS Blade 
http://opencompute.org 31 
 
10.8.5 Hot Swap Controller 
For in-rush current protection on the blade, an HSC that includes support for the PMBUS 1.2 
interface will be used on the motherboard. The device will support an I2C polling rate of 10ms. The 
HSC will be available to the Intel® ME SML1 and will provide its ALERT# signal to a Multipath 
General-Purpose Input/Output (MGPIO) on the PCH. The Intel ME SML1 will be dedicated to the 
HSC to provide fast response time to power excursions.  
Following is a list of devices known to be supported by the platform requirements (equivalent or 
newer devices may exist): 
 Analog Devices ADM1276 
 Texas Instruments LM25066i  
 Texas Instruments LM25062 
 Texas Instruments LM25063 
Intel® Node Manager requires the ability to read blade power levels from the HSC to detect 
conditions where total blade power exceeds the desired level for power capping. Operation of the 
HSC is controlled by the BLADE_EN1 and BLADE_MATED signals from the tray backplane, as 
described in the sections that follow. 
10.8.5.1 Blade Enable Signal 
The BLADE_EN1 signal is sourced from the Chassis Management Card (CMC) through the tray 
backplane. The signal is active high, and is intended to be connected to the EN input of the HSC. 
The signal driver from the CMC is open-drain. In normal operation, it will be pulled high through a 
resistive termination when a 3.3V regulator on the blade is enabled.  
To disable the power, the CMC pulls the Blade_EN1 signal to reference ground. The Blade_EN1 
signal should not be pulled low on the blade or driven back to the Chassis Manager. 
If BLADE_EN1 is used to disable power to the blade, the BMC will detect this event and disable 
logging to prevent spurious messages from propagating to the log files. 
10.8.5.2 Blade Mated Signal 
The active low Blade[1:2]_Mated_N signals are used to qualify Blade_EN to indicate that the 
connectors have properly mated during blade insertion before the 12V inrush power is turned on.  
These signals should be connected to the UV (undervoltage) input pin of the HSC. The mated signals 
are pulled to ground on the tray backplane through a 100 ohm (Ω) resistor. Both BLADE_MATED_N 
signals from the AirMax VS2 PCIe connector and the AirMax VS2 10/40GbE connector must be 
asserted before 12V inrush power is turned on. 



 
32 October 30, 2014 
 
To support potential blade or tray backplane SKUs in which connectors could be depopulated, the 
BLADE_MATED_N circuitry should allow for depopulation of components to meet the 
BLADE_MATED_N requirement from either connector. 
Figure 18 shows the signal connections and contact sequence. The 3.3V pull-ups shown should be 
derived from the 12V raw input. Note that the block diagram is intended to be functional only and 
does not describe the actual circuitry required for the intended logic. 
To support possible SKUs of the tray backplane in which connectors can be removed, the design 
should include a method for grounding the BLADE_EN1 pin from the PCIe AirMax connector in case 
this connector is depopulated. This could be accomplished through a BOM load or other methods.   
BLADE Motherboard Tray
Backplane
Tray Mezz
BLADE_EN1
12V
Conditioned
12V Raw
3.3V
BLADE_MATED_N
3.3V GbE Airmax
VS2
Airmax
Power
Short Pin
Short Pin
Long Pin
MINI
FIT
PDB
Edge
Finger
PCIe AirMax
VS2
Hot
Swap
Controller
PCIe AirMax
VS2
Short Pin
Long Pin
BLADE_MATED_N
3.3V
Vin
En
UV
 
Figure 18: HSC functional block diagram 
Following is the connector contact sequence: 
1. Guide pin (GND) engages. 
2. AirMax power connector (12V and GND) and AirMax VS2 long pin (GND) engage. 
o Blade_EN1 and both Blade_Mated_N are high on blade. 
o HSC is disabled. 
3. AirMax VS2 short pins engage.  



Open Compute Project  Open CloudServer OCS Blade 
http://opencompute.org 33 
 
o Blade_EN, Blade_Mated_N and all other signal pins engage. 
o Blade_EN1 is high and both Blade_Mated_N are low. 
o HSC is enabled.   
10.8.5.3 Signal Interpretation  
Table 21 describes the HSC controller with regards to the Blade_EN1 and Blade_Mated_N signals.  
Table 21: Signal interpretation 
BLADE_EN1  
on blade 
BLADE_MATED_N  
on blade Blade/hot swap controller status 
1 1 
 No 12V power, no signal connection to backplane 
 Blade was either not inserted or recently removed 
 Hot swap controller is DISABLED 
1  0 
 Blade is installed, 12V is present 
 Signal connector is mated 
 CM is either not present or is driving high 
 Hot swap controller is ENABLED 
0 1 
 Invalid or faulty state  
 The only way to drive BLADE_EN1 low is from the CM through 
the signal connector  
 If either BLADE_MATED_N is high, the connection was not made 
 Hot swap controller is DISABLED 
0 0 
 Blade is installed, 12V is present 
 Both Signal connector are mated 
 CM drives BLADE_EN1 low 
 Hot swap controller is DISABLED 
10.8.6 PCIe I2C 
The blade will support I2C for the tray mezzanine card and the NIC mezzanine card. It is expected 
that standard PCIe modules will support Address Resolution Protocol (ARP) per the I2C 
specification. This should be verified with the specification for specific mezzanine cards. The 
modules shall be accessible to the I2C ports as shown in the block diagram. 
10.9 Intel® Node Manager Hardware Requirements 
Blade management will meet the hardware requirements for support of Intel® Node Manager.  The 
requirements include, but are not limited, to the following: 
 The Intel ME shall be enabled (powered) in all states (i.e., must be power from AUX power). 



 
34 October 30, 2014 
 
 The following signals will be driven or received MGPIO signals of the PCH (additional 
SmaRT/CLST logic will be supported on the PCB): 
o 12V HSC ALERT# 
o SMBAlert#, SMBAlert_EN# 
o PROCHOT# and MEMHOT# for each CPU 
10.10 Blade LEDs 
The following sections describe the light-emitting diodes (LEDs) used as indicators on the blades 
and chassis. 
Each blade has three LEDs: a front power/status LED that is green/amber, and two attention LEDs 
(front and back) that are red. Figure 19 shows the location of the front LEDs. The location of the 
rear LED is shown in Figure 20. The visible diameter and brightness requirements of the LEDs are 
TBD.  
 
Figure 19: Front blade LED locations 
The rear attention LED is located near the AirMax 3x6 SAS connector, as shown in Figure 20. The 
LED is placed so that it is visible externally through the blade and tray backplane connectors.  
 


Open Compute Project  Open CloudServer OCS Blade 
http://opencompute.org 35 
 
Figure 20: Rear attention LED location 
10.10.1 Blade Power Status LED 
When a blade is first inserted, the LED will turn amber if 12V is present at the output of the HSC. 
This ensures that the backplane has 12V power, the tray backplane connectors are mated, and the 
Blade_EN1 signal is asserted.  
When the blade’s management software turns on the system power (CPU/Memory/PCIe), the 
power status LED turns green. Note that the power status LED may be driven by an analog resistor 
network tied directly to a power rail, and is not an indication of the health of the blade. Table 22 
describes the operation of the blade power status LED. 
Table 22: Blade power status LED description 
LED status Condition 
Off Blade is not fully inserted, 12V power is absent, or Blade_EN1 is de-asserted. 
Solid Amber ON Blade is inserted, Blade_EN1 is asserted, 12V power output from the Hot Swap 
Controller is present.  
Solid Green ON Indicates that the BMC is booted and system power is enabled 
(CPU/Memory/PCIe). 
10.10.2 Blade Attention LED 
The blade attention LED directs the service technicians to the blade that requires repair. The 
technician can remove the blade from the rack and replace it with an operational blade.  
The attention LED is driven by a single BMC GPIO. Table 23 describes the operation of the blade 
attention LED. 
Table 23: Blade attention LED description 
LED status Condition 
Off No attention indicated. 
Solid RED System needs attention. 
Note that a second red Attention LED is located at the rear of the blade so that it is visible through 
the tray when the fan door is opened. This LED is set at the same time as the front red attention 
LED, and indicates from the rear of the chassis which blade needs attention. 



 
36 October 30, 2014 
 
10.11 Debug Features 
The following minimum debug features will be included on the motherboard during pre-
production: 
 I2C debug headers on the CPU SMBus, PCH SMBus, Intel ME SML I2C, and BMC I2C.   
Header will be a 3-pin compatible with standard I2C protocol analyzers (such as Beagle Protocol 
Analyzer or Aardvark Host Adapter).  
Note that the CPU SMBus can be eventually accessed through CPU XDP connector. 
 Debug connector on all three BMC UARTS as shown in the block diagram (Figure 15).   
Connector TBD. 
 Port 80 POST LED support on LPC bus as shown in the block diagram (Figure 15). 
 BIOS debug support including: 
o Socketed BIOS Flash (to be removed for production) 
o BIOS recovery jumper connected to PCH GPIO 
o Flash security override driven from BMC GPIO (to PCH) 
 Power button support. 
 CPU XDP.  
Recommend support for ITP60c, or otherwise ensure that it will be mechanically possible to 
solder on the XDP connector post-production for debug. 
 Dual USB 2.0 headers connected to PCH USB2 Port 1 and Port 9.  
Dongles will be readily available to get standard USB connectors (Port 1 on EHCI#1 and Port 9 on 
EHCI#2 [assuming 0-based numbering] of PCH).  
 USB 2.0 debug port connected to PCH USB2 Port 0 for BIOS and OS debug.   
These can be implemented using 4-pin header connectors to save space. 
 BMC disable jumper attached to GPIO on BMC. 
 Intel ME recovery mode jumper. 
 HW jumper to enable BIOS serial debug output. 
Placement of the debug connectors will not obstruct the installation of any optional assemblies 
such as the PCIe RAID Card or SSDs.  It is acceptable that a debug feature is not accessible if an 
optional assembly is installed unless the feature supports debug of that optional assembly. 
10.12 Tray Mezzanine Power Control 
The 12V power to the tray mezzanine is sourced directly from the output of the Hot Swap 
Controller, and is therefore always present when the HSC is enabled. MEZZ_EN is provided as a 
means to disable power to the tray mezzanine without removing power from the blade. 



Open Compute Project  Open CloudServer OCS Blade 
http://opencompute.org 37 
 
10.13 Connector Quality 
The V2.0 Open CloudServer is designed for use in datacenters with a wide range of humidity (up to 
90%). The connectors for these deployments must be capable of withstanding high humidity during 
shipping and installation. The baseline for plating DIMMs and PCIe connectors will be 30μ”-thick 
gold. DIMM connectors must also include lubricant/sealant applied by the connector manufacturer 
that can remain intact after soldering and other manufacturing processes. The sealant is required 
to displace any voids in the connector gold plating. 
10.14 Overcurrent Protection 
The hot swap controller (HSC) and associated circuitry is responsible for monitoring the 12V input 
current to the blade.  There are two levels of overcurrent protection associated with this monitoring.   
 Over-current protection is responsible for detecting a current level that indicates a catastrophic 
failure of the blade.  In this event, the HSC should disable 12V to the blade typically by disabling 
the HSC’s input FETS.  The recommended current threshold for over-current protection is 50A. 
 Over-current monitor is responsible for detecting a current level that which is higher than 
achievable limits by worst case applications.  In this event, the blade typically throttles the CPU 
performance using the PROCHOT# input.  It is expected that the current threshold be set high 
enough or with slow enough filter response to prevent throttling during performance or stress 
testing with worst case configuration.  The recommended current threshold for over-current 
monitoring is 45A. 
11 NIC Mezzanine 
The V2.0 OCS motherboard will support a 40GbE or 10GbE NIC mezzanine card. The network 
controller on the NIC mezzanine will interface to CPU0 through a PCIe x8 channel.  10GbE is 
supported though Port 1 of the NIC to the blade connector interface, and 40GbE is supported 
through Port 2 of the NIC to the blade connector interface. The 10G port will connect to an SFP+ 
connector on the tray backplane. The 40G port will connect to a QSFP+ connector on the tray 
backplane. Figure 21 shows the NIC block diagram. The pinout for the NIC mezzanine is described in 
Section 9.3. Mechanical outlines can be found in the Open CloudServer OCS NIC Mezzanine 
Specification Version 2.0. 



 
38 October 30, 2014 
 
Blade Motherboard
  
 NIC Mezz
Tray Backplane
Airmax
VS2
Airmax
VS2
        40GbE
     Controller
10GbE Port
40GbE Port
SEAM SEAF
Port 2
Port 1
L0
L1
L2
L3
L0
L1
L2
L3
Retimer
DS110DF111
          10G
     Controller
L2
L3
L1
L0
L0 L0
L1
L2
L3
L0
L1
L2
L3
Port 2
Port 1
PCIe
CPU0
PCIe PCIe
Network
SwitchCable
< 3m
Network
SwitchCable
< 3m<1.6"<3.5"
<1" <0.9"
SFP+
QSFP+
L3
L2
L1
L0
L0
 
Figure 21:  NIC block diagram 
12 Blade Electrical Specifications 
The following sections provide specifications for the blade input voltage and current, as well as the 
primary blade signals. 
12.1 Input Voltage, Power, and Current 
Table 24 lists the nominal, maximum, and minimum values for the blade input voltage. The 
maximum and minimum voltages include the effects of connector temperature, age, noise/ripple, 
and dynamic loading. 
Table 24: Input voltage range 
Nominal voltage Maximum voltage Minimum voltage 
12.3V DC 14V DC 11V DC 
The maximum amount of power allowed per blade is defined during system power allocation. The 
number of blades in a chassis might be limited by the capacity of the AC power cord or by the 
cooling capacity of the deployment. Table 25 lists the input power allocation for a low-power blade. 
Table 25: Input power and current allocation 
 Nominal voltage System power allocation 
to blade assembly (in W) Allocated current (in A) 
Low-power blade 
(1x power connector) 12.3VDC 300W 30A 
The blade provides inrush current control through the 12V bus rail; return-side inrush control is not 
used. The inrush current rises linearly from 0A to the load current over a 5 millisecond (ms) period. 



Open Compute Project  Open CloudServer OCS Blade 
http://opencompute.org 39 
 
12.2 Current Interrupt Protection and Power, Voltage, and Current 
Monitoring 
The blade provides a cost-effective way to measure and report blade voltage and current 
consumption, and to make instance reporting available to the system. The blade will include power 
consumption measurements at the inrush controller.  Accuracy of the measurement will be +/- 2%.  
The blade also provides a way to interrupt current flow within 1 microsecond (μs) of exceeding the 
maximum current load. 
12.3 Filtering and Capacitance 
The blade provides sufficient filtering to operate with a 0.25A/ μs DC source.  
Maximum capacitance allowed on the 12V input to the blade is 4,000μFarads (μF). Minimum 
capacitance allowed per blade is 300μF. 
12.4 Grounding and Return 
The blade chassis grounding/return is provided to the blade from the tray backplane through the 
tray backplane/blade interface connectors, including the 12V power connector, guide pins, and 
signal connectors. Chassis ground and logic ground are tied together on the tray backplane and 
should not be separated on the blade. 
13 Blade Physical Specifications 
The physical specifications for the blades include the dimensions of the space into which the blade 
is installed, blade weight limits, a description of the guiding and latching features, and information 
about electromagnetic interference shielding. 
13.1 Blade Mechanical Control Outline 
Figure 22 shows the outline for the blade mechanical controls; note that the locations shown for 
the connectors interfacing to the tray backplane are mandatory, but locations for other connectors, 
components, and mounting holes are suggestions and can be modified to meet the requirements of 
the PCB implementation.  



 
40 October 30, 2014 
 
 Mounting holes 
Figure 22 provides guidelines for mounting holes; actual mounting hole locations may vary to 
meet PCB implementation requirements. 
 NIC mezzanine keepout 
Figure 22 does not include component height restrictions for the NIC mezzanine. For 
information concerning the component height restrictions, see Open CloudServer NIC Mezzanine 
Specification Version 2.0. 
 RAID/ROC card 
Figure 22 shows the component height restrictions for supporting PCIe cards, such as the 
RAID/RAID on Chip (ROC).  Note that the RAID card can include a local Supercap or battery 
backup solution; mounting for this should be accounted for by the mechanical design. 
 
Figure 22: Mechanical control outline 


Open Compute Project  Open CloudServer OCS Blade 
http://opencompute.org 41 
 
13.2 Volumetric Specifications 
The outer surfaces of the blade must fit into the volume defined in Figure 23, with all tolerances 
and manufacturing methods accounted for; no features of the blade (including the latch and the 
handle) can extend beyond the specified distance from the front column of the rack so that the 
front door of the rack can be closed without interference.  
This specification assumes a coplanar power/network distribution PCB; if another structure is used, 
the connectors need to be form, fit, and functionally compatible with this specification. Note that if 
necessary, an electromagnetic interference (EMI) enclosure can be built to fit within the volumetric 
restrictions.  
 
 
Figure 23: Dimensions of the volume that holds the blade 
Each rack unit (or level) within the chassis enclosure can accommodate either two half-width blades 
inserted next to each other or a single full-width blade. Figure 24 shows two blades on a tray.  



 
42 October 30, 2014 
 
 
 
Figure 24: Two blades on a single tray 
Figure 25 shows the dimensions of the blade-mounting envelope, which holds the blade on the 
tray.  


Open Compute Project  Open CloudServer OCS Blade 
http://opencompute.org 43 
 
 
Figure 25: Blade-mounting envelope, rear view 
Note that the only serviceable components in the blade are the hard drives, which can be replaced 
without tools. All other repairs to the blade are made in a bench-top environment. Components 


 
44 October 30, 2014 
 
such as heat sinks, hard drives, and mother boards can be attached so that removal requires a tool, 
if this option is less expensive. 
13.3 Weight and Structure 
Because the tray can support a total weight of 50 lbs, a standard blade should not exceed a static 
weight of 25 lbs when loaded with all options.  
The blade must be mechanically stiff enough to support its own weight during shipping and 
handling. The side walls of the blade should be made as tall as possible within the given envelope to 
maximize the stiffness of the blade structure. 
The blade shall contain a dimple on the side of the front surface to force the blades to fit tightly in 
the tray and prevent excessive bowing in the trays during a shock.  Figure 26 shows an example. 
 
Figure 26: Front surface dimple 
13.4 Guiding and Latching Features 
The sections that follow describe guiding and latching features for the blade. 
13.4.1 Latching Feature Identification 
Latches, as well as thumb screws and other components used to lock, unlock, or remove a 
subassembly from the chassis, are colored blue (Pantone code 285 C blue) to make them easy to 
identify. The locking feature used to secure the blade latch to the front of the blade must provide 
locking with minimal hand motion. A screw type lock with more than a half-turn rotation is not 
permitted. 


Open Compute Project  Open CloudServer OCS Blade 
http://opencompute.org 45 
 
If the identity and function of a latching feature for a particular field replaceable unit (FRU) is clear, 
coloring might not be required. For example, a lock/unlock indicator is sufficient for a blade lever. 
13.4.2 Guiding and Latching 
Because a single tray design without a center rail is used for both half-width and full-width blades, 
guides and alignment features are located in both the front and back of the enclosure. These 
features are especially important when inserting a half-width blade into an empty tray.  
The blade enclosure interfaces with the side walls of the tray and the guide pin in the tray to make 
sure the blade is aligned within the ±3.50mm (±0.138”) tolerance necessary to engage the 
connector. The guide pin in the tray aligns the half-width blades with the correct side of the tray. 
The blade connectors are protected from damage by the guide pin by the blade sheet metal. 
Figure 27 shows the blade guiding and latching features associated with the tray. Blade guide pins 
slide into slots on the front of the tray for alignment. A latch attached to the blade fits into a notch 
in the tray to secure the blade in place. 



 
46 October 30, 2014 
 
 
Figure 27: Guide and latch details, top view 
Figure 28 and Figure 29 show examples of a front-blade guide and latch and of a rear-blade guide.  
Note that a lever is included at the front of the blade to provide additional guidance when the 
blade is locking into the tray, and to help with the force required to install and remove the blade 
from the tray. 


Open Compute Project  Open CloudServer OCS Blade 
http://opencompute.org 47 
 
  
Figure 28. Example of a front-blade guide and latch 
 
Figure 29: Example of a rear-blade guide pin 
13.4.3 Electromagnetic Interference Mitigation 
For EMI containment, an EMI shield is added to the top rear edge of the tray, as shown in Figure 30. 
EMI containment will be executed at the blade-assembly level, and EMI certification will be 
executed at the chassis level. 


 
48 October 30, 2014 
 
 
Figure 30: Tray with EMI enclosure, blade volume shown 
When all trays are in place, they are electrically stitched together to prevent leakage of 
electromagnetic fields. The blade also has a gasket on the front of the top surface that provides 
electrical sealing, as shown in Figure 31. Dimensions for this gasket are shown in Figure 23. 
 
Figure 31: Blade EMI seal 
14 Blade Thermal Design 
To achieve high reliability required for use at scale, the blade must be designed to meet or exceed 
the thermal specifications of all components.  Since the fans used to cool the blades are shared 
with other blades within the chassis, the blades are to be designed to operate according to the 
impedance and airflow curves provided in the Cooling System Specifications chapter of the Open 
CloudServer OCS Chassis Specification Version 2.0 document.  Fan operation and communication 
with chassis management software to set the fan speed are fully described in that chapter. 
 
